(kicad_pcb
	(version 20260206)
	(generator "pcbnew")
	(generator_version "10.0")
	(general
		(thickness 1.6)
		(legacy_teardrops no)
	)
	(paper "A4")
	(title_block
		(title "baseboard — 13948-1b.1110WZS1818.brd")
		(comment 1 "Honey Badger (Wiwynn) / footprints 85-93 of 2523")
	)
	(layers
		(0 "F.Cu" signal "TOP")
		(4 "In1.Cu" signal "L2GND")
		(6 "In2.Cu" signal "L3")
		(8 "In3.Cu" signal "L4VCC")
		(10 "In4.Cu" signal "L5VCC")
		(12 "In5.Cu" signal "L6")
		(14 "In6.Cu" signal "L7GND")
		(2 "B.Cu" signal "BOTTOM")
		(9 "F.Adhes" user "F.Adhesive")
		(11 "B.Adhes" user "B.Adhesive")
		(13 "F.Paste" user "Package Geometry/Pastemask Top")
		(15 "B.Paste" user "Package Geometry/Pastemask Bottom")
		(5 "F.SilkS" user "Ref Des/Silkscreen Top")
		(7 "B.SilkS" user "Ref Des/Silkscreen Bottom")
		(1 "F.Mask" user "Board Geometry/Soldermask Top")
		(3 "B.Mask" user "Board Geometry/Soldermask Bottom")
		(17 "Dwgs.User" user "User.Drawings")
		(19 "Cmts.User" user "User.Comments")
		(21 "Eco1.User" user "User.Eco1")
		(23 "Eco2.User" user "User.Eco2")
		(25 "Edge.Cuts" user "Board Geometry/Outline")
		(27 "Margin" user)
		(31 "F.CrtYd" user "Package Geometry/Place Bound Top")
		(29 "B.CrtYd" user "Package Geometry/Place Bound Bottom")
		(35 "F.Fab" user "Ref Des/Assembly Top")
		(33 "B.Fab" user "Ref Des/Assembly Bottom")
	)
	(footprint ""
		(layer "F.Cu")
		(at 209.931 -103.124 180)
		(property "Reference" "PC141"
			(at 0 0 180)
			(layer "F.SilkS")
			(hide yes)
			(effects
				(font
					(size 1.27 1.27)
				)
			)
		)
		(property "Value" "SC1KP50V2KX-1GP"
			(at 1.1811 -2.7051 180)
			(unlocked yes)
			(layer "F.Fab")
			(hide yes)
			(effects
				(font
					(size 1.016 1.016)
					(thickness 0.1524)
				)
			)
		)
		(property "Device Type" "C402H22"
			(at 1.1811 -4.2291 180)
			(unlocked yes)
			(layer "F.Fab")
			(hide yes)
			(effects
				(font
					(size 1.016 1.016)
					(thickness 0.1524)
				)
			)
		)
		(duplicate_pad_numbers_are_jumpers no)
		(fp_rect
			(start -0.4318 0.9525)
			(end 0.4318 -0.9525)
			(stroke
				(width 0)
				(type default)
			)
			(fill no)
			(layer "F.CrtYd")
		)
		(fp_rect
			(start -0.4318 0.9525)
			(end 0.4318 -0.9525)
			(stroke
				(width 0)
				(type default)
			)
			(fill no)
			(layer "F.Fab")
		)
		(pad "1" smd custom
			(at 0 -0.4445 180)
			(size 0.1524 0.1524)
			(layers "F.Cu" "F.Mask" "F.Paste")
			(net "P1V5_C")
			(options
				(clearance outline)
				(anchor circle)
			)
			(primitives
				(gr_poly
					(pts
						(arc
							(start 0.3048 -0.2032)
							(mid 0.275042 -0.275042)
							(end 0.2032 -0.3048)
						)
						(arc
							(start -0.2032 -0.3048)
							(mid -0.275042 -0.275042)
							(end -0.3048 -0.2032)
						)
						(arc
							(start -0.3048 0.2032)
							(mid -0.275042 0.275042)
							(end -0.2032 0.3048)
						)
						(arc
							(start 0.2032 0.3048)
							(mid 0.275042 0.275042)
							(end 0.3048 0.2032)
						)
					)
					(width 0)
					(fill yes)
				)
			)
		)
		(pad "2" smd custom
			(at 0 0.4445 180)
			(size 0.1524 0.1524)
			(layers "F.Cu" "F.Mask" "F.Paste")
			(net "TPS74801_1V5_C_FB")
			(options
				(clearance outline)
				(anchor circle)
			)
			(primitives
				(gr_poly
					(pts
						(arc
							(start 0.3048 -0.2032)
							(mid 0.275042 -0.275042)
							(end 0.2032 -0.3048)
						)
						(arc
							(start -0.2032 -0.3048)
							(mid -0.275042 -0.275042)
							(end -0.3048 -0.2032)
						)
						(arc
							(start -0.3048 0.2032)
							(mid -0.275042 0.275042)
							(end -0.2032 0.3048)
						)
						(arc
							(start 0.2032 0.3048)
							(mid 0.275042 0.275042)
							(end 0.3048 0.2032)
						)
					)
					(width 0)
					(fill yes)
				)
			)
		)
	)
	(footprint ""
		(layer "F.Cu")
		(at 220.345 -118.745 -90)
		(property "Reference" "R604"
			(at 0 0 270)
			(layer "F.SilkS")
			(hide yes)
			(effects
				(font
					(size 1.27 1.27)
				)
			)
		)
		(property "Value" "1KR2J-1-GP"
			(at 0.064008 -3.993896 270)
			(unlocked yes)
			(layer "F.Fab")
			(hide yes)
			(effects
				(font
					(size 1.016 1.016)
					(thickness 0.1524)
				)
			)
		)
		(property "Device Type" "R402H16"
			(at 0.064008 -5.517896 270)
			(unlocked yes)
			(layer "F.Fab")
			(hide yes)
			(effects
				(font
					(size 1.016 1.016)
					(thickness 0.1524)
				)
			)
		)
		(duplicate_pad_numbers_are_jumpers no)
		(fp_line
			(start -0.508 -0.9398)
			(end -0.508 0.9398)
			(stroke
				(width 0.1524)
				(type default)
			)
			(layer "F.SilkS")
		)
		(fp_line
			(start 0.508 -0.9398)
			(end -0.508 -0.9398)
			(stroke
				(width 0.1524)
				(type default)
			)
			(layer "F.SilkS")
		)
		(fp_rect
			(start -0.508 0.9398)
			(end 0.508 -0.9398)
			(stroke
				(width 0)
				(type default)
			)
			(fill no)
			(layer "F.CrtYd")
		)
		(fp_rect
			(start -0.508 0.9398)
			(end 0.508 -0.9398)
			(stroke
				(width 0)
				(type default)
			)
			(fill no)
			(layer "F.Fab")
		)
		(pad "1" smd custom
			(at 0 -0.4445 270)
			(size 0.1397 0.1397)
			(layers "F.Cu" "F.Mask" "F.Paste")
			(net "P3V3_STBY_R3")
			(options
				(clearance outline)
				(anchor circle)
			)
			(primitives
				(gr_poly
					(pts
						(arc
							(start -0.1778 -0.2794)
							(mid -0.249642 -0.249642)
							(end -0.2794 -0.1778)
						)
						(arc
							(start -0.2794 0.1778)
							(mid -0.249642 0.249642)
							(end -0.1778 0.2794)
						)
						(arc
							(start 0.1778 0.2794)
							(mid 0.249642 0.249642)
							(end 0.2794 0.1778)
						)
						(arc
							(start 0.2794 -0.1778)
							(mid 0.249642 -0.249642)
							(end 0.1778 -0.2794)
						)
					)
					(width 0)
					(fill yes)
				)
			)
		)
		(pad "2" smd custom
			(at 0 0.4445 270)
			(size 0.1397 0.1397)
			(layers "F.Cu" "F.Mask" "F.Paste")
			(net "P3V3_STBY")
			(options
				(clearance outline)
				(anchor circle)
			)
			(primitives
				(gr_poly
					(pts
						(arc
							(start -0.1778 -0.2794)
							(mid -0.249642 -0.249642)
							(end -0.2794 -0.1778)
						)
						(arc
							(start -0.2794 0.1778)
							(mid -0.249642 0.249642)
							(end -0.1778 0.2794)
						)
						(arc
							(start 0.1778 0.2794)
							(mid 0.249642 0.249642)
							(end 0.2794 0.1778)
						)
						(arc
							(start 0.2794 -0.1778)
							(mid 0.249642 -0.249642)
							(end 0.1778 -0.2794)
						)
					)
					(width 0)
					(fill yes)
				)
			)
		)
	)
	(footprint ""
		(layer "F.Cu")
		(at 200.348596 -121.177812)
		(property "Reference" "PR9010"
			(at 0 0 0)
			(layer "F.SilkS")
			(hide yes)
			(effects
				(font
					(size 1.27 1.27)
				)
			)
		)
		(property "Value" "10KR2F-2-GP"
			(at 0.064008 -3.993896 0)
			(unlocked yes)
			(layer "F.Fab")
			(hide yes)
			(effects
				(font
					(size 1.016 1.016)
					(thickness 0.1524)
				)
			)
		)
		(property "Device Type" "R402H16"
			(at 0.064008 -5.517896 0)
			(unlocked yes)
			(layer "F.Fab")
			(hide yes)
			(effects
				(font
					(size 1.016 1.016)
					(thickness 0.1524)
				)
			)
		)
		(duplicate_pad_numbers_are_jumpers no)
		(fp_line
			(start -0.508 -0.9398)
			(end -0.508 0.9398)
			(stroke
				(width 0.1524)
				(type default)
			)
			(layer "F.SilkS")
		)
		(fp_line
			(start 0.508 -0.9398)
			(end -0.508 -0.9398)
			(stroke
				(width 0.1524)
				(type default)
			)
			(layer "F.SilkS")
		)
		(fp_rect
			(start -0.508 0.9398)
			(end 0.508 -0.9398)
			(stroke
				(width 0)
				(type default)
			)
			(fill no)
			(layer "F.CrtYd")
		)
		(fp_rect
			(start -0.508 0.9398)
			(end 0.508 -0.9398)
			(stroke
				(width 0)
				(type default)
			)
			(fill no)
			(layer "F.Fab")
		)
		(pad "1" smd custom
			(at 0 -0.4445)
			(size 0.1397 0.1397)
			(layers "F.Cu" "F.Mask" "F.Paste")
			(net "AGND_P1V5_E")
			(options
				(clearance outline)
				(anchor circle)
			)
			(primitives
				(gr_poly
					(pts
						(arc
							(start -0.1778 -0.2794)
							(mid -0.249642 -0.249642)
							(end -0.2794 -0.1778)
						)
						(arc
							(start -0.2794 0.1778)
							(mid -0.249642 0.249642)
							(end -0.1778 0.2794)
						)
						(arc
							(start 0.1778 0.2794)
							(mid 0.249642 0.249642)
							(end 0.2794 0.1778)
						)
						(arc
							(start 0.2794 -0.1778)
							(mid 0.249642 -0.249642)
							(end 0.1778 -0.2794)
						)
					)
					(width 0)
					(fill yes)
				)
			)
		)
		(pad "2" smd custom
			(at 0 0.4445)
			(size 0.1397 0.1397)
			(layers "F.Cu" "F.Mask" "F.Paste")
			(net "P1V5_E_VFB")
			(options
				(clearance outline)
				(anchor circle)
			)
			(primitives
				(gr_poly
					(pts
						(arc
							(start -0.1778 -0.2794)
							(mid -0.249642 -0.249642)
							(end -0.2794 -0.1778)
						)
						(arc
							(start -0.2794 0.1778)
							(mid -0.249642 0.249642)
							(end -0.1778 0.2794)
						)
						(arc
							(start 0.1778 0.2794)
							(mid 0.249642 0.249642)
							(end 0.2794 0.1778)
						)
						(arc
							(start 0.2794 -0.1778)
							(mid 0.249642 -0.249642)
							(end 0.1778 -0.2794)
						)
					)
					(width 0)
					(fill yes)
				)
			)
		)
	)
	(footprint ""
		(layer "F.Cu")
		(at 256.159 -136.779 180)
		(property "Reference" "SC1303"
			(at 0 0 180)
			(layer "F.SilkS")
			(hide yes)
			(effects
				(font
					(size 1.27 1.27)
				)
			)
		)
		(property "Value" "SCD1U16V2KX-3GP"
			(at 1.1811 -2.7051 180)
			(unlocked yes)
			(layer "F.Fab")
			(hide yes)
			(effects
				(font
					(size 1.016 1.016)
					(thickness 0.1524)
				)
			)
		)
		(property "Device Type" "C402H22"
			(at 1.1811 -4.2291 180)
			(unlocked yes)
			(layer "F.Fab")
			(hide yes)
			(effects
				(font
					(size 1.016 1.016)
					(thickness 0.1524)
				)
			)
		)
		(duplicate_pad_numbers_are_jumpers no)
		(fp_rect
			(start -0.4318 0.9525)
			(end 0.4318 -0.9525)
			(stroke
				(width 0)
				(type default)
			)
			(fill no)
			(layer "F.CrtYd")
		)
		(fp_rect
			(start -0.4318 0.9525)
			(end 0.4318 -0.9525)
			(stroke
				(width 0)
				(type default)
			)
			(fill no)
			(layer "F.Fab")
		)
		(pad "1" smd custom
			(at 0 -0.4445 180)
			(size 0.1524 0.1524)
			(layers "F.Cu" "F.Mask" "F.Paste")
			(net "P3V3_STBY")
			(options
				(clearance outline)
				(anchor circle)
			)
			(primitives
				(gr_poly
					(pts
						(arc
							(start 0.3048 -0.2032)
							(mid 0.275042 -0.275042)
							(end 0.2032 -0.3048)
						)
						(arc
							(start -0.2032 -0.3048)
							(mid -0.275042 -0.275042)
							(end -0.3048 -0.2032)
						)
						(arc
							(start -0.3048 0.2032)
							(mid -0.275042 0.275042)
							(end -0.2032 0.3048)
						)
						(arc
							(start 0.2032 0.3048)
							(mid 0.275042 0.275042)
							(end 0.3048 0.2032)
						)
					)
					(width 0)
					(fill yes)
				)
			)
		)
		(pad "2" smd custom
			(at 0 0.4445 180)
			(size 0.1524 0.1524)
			(layers "F.Cu" "F.Mask" "F.Paste")
			(net "GND")
			(options
				(clearance outline)
				(anchor circle)
			)
			(primitives
				(gr_poly
					(pts
						(arc
							(start 0.3048 -0.2032)
							(mid 0.275042 -0.275042)
							(end 0.2032 -0.3048)
						)
						(arc
							(start -0.2032 -0.3048)
							(mid -0.275042 -0.275042)
							(end -0.3048 -0.2032)
						)
						(arc
							(start -0.3048 0.2032)
							(mid -0.275042 0.275042)
							(end -0.2032 0.3048)
						)
						(arc
							(start 0.2032 0.3048)
							(mid 0.275042 0.275042)
							(end 0.3048 0.2032)
						)
					)
					(width 0)
					(fill yes)
				)
			)
		)
	)
	(footprint ""
		(layer "F.Cu")
		(at 191.516 -145.034 -90)
		(property "Reference" "SR737"
			(at 0 0 270)
			(layer "F.SilkS")
			(hide yes)
			(effects
				(font
					(size 1.27 1.27)
				)
			)
		)
		(property "Value" "2K2R2F-GP"
			(at 0.064008 -3.993896 270)
			(unlocked yes)
			(layer "F.Fab")
			(hide yes)
			(effects
				(font
					(size 1.016 1.016)
					(thickness 0.1524)
				)
			)
		)
		(property "Device Type" "R402H16"
			(at 0.064008 -5.517896 270)
			(unlocked yes)
			(layer "F.Fab")
			(hide yes)
			(effects
				(font
					(size 1.016 1.016)
					(thickness 0.1524)
				)
			)
		)
		(duplicate_pad_numbers_are_jumpers no)
		(fp_line
			(start -0.508 -0.9398)
			(end -0.508 0.9398)
			(stroke
				(width 0.1524)
				(type default)
			)
			(layer "F.SilkS")
		)
		(fp_line
			(start 0.508 -0.9398)
			(end -0.508 -0.9398)
			(stroke
				(width 0.1524)
				(type default)
			)
			(layer "F.SilkS")
		)
		(fp_rect
			(start -0.508 0.9398)
			(end 0.508 -0.9398)
			(stroke
				(width 0)
				(type default)
			)
			(fill no)
			(layer "F.CrtYd")
		)
		(fp_rect
			(start -0.508 0.9398)
			(end 0.508 -0.9398)
			(stroke
				(width 0)
				(type default)
			)
			(fill no)
			(layer "F.Fab")
		)
		(pad "1" smd custom
			(at 0 -0.4445 270)
			(size 0.1397 0.1397)
			(layers "F.Cu" "F.Mask" "F.Paste")
			(net "EXP_I2C_SDA_3")
			(options
				(clearance outline)
				(anchor circle)
			)
			(primitives
				(gr_poly
					(pts
						(arc
							(start -0.1778 -0.2794)
							(mid -0.249642 -0.249642)
							(end -0.2794 -0.1778)
						)
						(arc
							(start -0.2794 0.1778)
							(mid -0.249642 0.249642)
							(end -0.1778 0.2794)
						)
						(arc
							(start 0.1778 0.2794)
							(mid 0.249642 0.249642)
							(end 0.2794 0.1778)
						)
						(arc
							(start 0.2794 -0.1778)
							(mid 0.249642 -0.249642)
							(end 0.1778 -0.2794)
						)
					)
					(width 0)
					(fill yes)
				)
			)
		)
		(pad "2" smd custom
			(at 0 0.4445 270)
			(size 0.1397 0.1397)
			(layers "F.Cu" "F.Mask" "F.Paste")
			(net "P1V8_E")
			(options
				(clearance outline)
				(anchor circle)
			)
			(primitives
				(gr_poly
					(pts
						(arc
							(start -0.1778 -0.2794)
							(mid -0.249642 -0.249642)
							(end -0.2794 -0.1778)
						)
						(arc
							(start -0.2794 0.1778)
							(mid -0.249642 0.249642)
							(end -0.1778 0.2794)
						)
						(arc
							(start 0.1778 0.2794)
							(mid 0.249642 0.249642)
							(end 0.2794 0.1778)
						)
						(arc
							(start 0.2794 -0.1778)
							(mid 0.249642 -0.249642)
							(end 0.1778 -0.2794)
						)
					)
					(width 0)
					(fill yes)
				)
			)
		)
	)
	(footprint ""
		(layer "F.Cu")
		(at 82.94497 -111.76 180)
		(property "Reference" "SC1206"
			(at 0 0 180)
			(layer "F.SilkS")
			(hide yes)
			(effects
				(font
					(size 1.27 1.27)
				)
			)
		)
		(property "Value" "SC10U6D3V5KX-4GP"
			(at -0.0762 -6.1214 180)
			(unlocked yes)
			(layer "F.Fab")
			(hide yes)
			(effects
				(font
					(size 1.016 1.016)
					(thickness 0.1524)
				)
			)
		)
		(property "Device Type" "C805H58"
			(at -0.0762 -8.1534 180)
			(unlocked yes)
			(layer "F.Fab")
			(hide yes)
			(effects
				(font
					(size 1.016 1.016)
					(thickness 0.1524)
				)
			)
		)
		(duplicate_pad_numbers_are_jumpers no)
		(fp_line
			(start 0.635 0)
			(end -0.635 0)
			(stroke
				(width 0.508)
				(type default)
			)
			(layer "F.SilkS")
		)
		(fp_rect
			(start -0.9652 1.778)
			(end 0.9652 -1.778)
			(stroke
				(width 0)
				(type default)
			)
			(fill no)
			(layer "F.CrtYd")
		)
		(fp_poly
			(pts
				(xy -0.9652 -1.778) (xy 0.9652 -1.778) (xy 0.9652 1.778) (xy -0.9652 1.778)
			)
			(stroke
				(width 0)
				(type default)
			)
			(fill no)
			(layer "F.Fab")
		)
		(pad "1" smd rect
			(at 0 -0.9652 180)
			(size 1.397 1.143)
			(layers "F.Cu" "F.Mask" "F.Paste")
			(net "P1V8_E")
		)
		(pad "2" smd rect
			(at 0 0.9652 180)
			(size 1.397 1.143)
			(layers "F.Cu" "F.Mask" "F.Paste")
			(net "GND")
		)
	)
	(footprint ""
		(layer "F.Cu")
		(at 174.107348 -125.847856 90)
		(property "Reference" "PC171"
			(at 0 0 90)
			(layer "F.SilkS")
			(hide yes)
			(effects
				(font
					(size 1.27 1.27)
				)
			)
		)
		(property "Value" "SC22U25V5MX-GP"
			(at -0.0762 -6.1214 90)
			(unlocked yes)
			(layer "F.Fab")
			(hide yes)
			(effects
				(font
					(size 1.016 1.016)
					(thickness 0.1524)
				)
			)
		)
		(property "Device Type" "C805H58"
			(at -0.0762 -8.1534 90)
			(unlocked yes)
			(layer "F.Fab")
			(hide yes)
			(effects
				(font
					(size 1.016 1.016)
					(thickness 0.1524)
				)
			)
		)
		(duplicate_pad_numbers_are_jumpers no)
		(fp_line
			(start 0.635 0)
			(end -0.635 0)
			(stroke
				(width 0.508)
				(type default)
			)
			(layer "F.SilkS")
		)
		(fp_rect
			(start -0.9652 1.778)
			(end 0.9652 -1.778)
			(stroke
				(width 0)
				(type default)
			)
			(fill no)
			(layer "F.CrtYd")
		)
		(fp_poly
			(pts
				(xy -0.9652 -1.778) (xy 0.9652 -1.778) (xy 0.9652 1.778) (xy -0.9652 1.778)
			)
			(stroke
				(width 0)
				(type default)
			)
			(fill no)
			(layer "F.Fab")
		)
		(pad "1" smd rect
			(at 0 -0.9652 90)
			(size 1.397 1.143)
			(layers "F.Cu" "F.Mask" "F.Paste")
			(net "P0V9_E_VIN")
		)
		(pad "2" smd rect
			(at 0 0.9652 90)
			(size 1.397 1.143)
			(layers "F.Cu" "F.Mask" "F.Paste")
			(net "GND")
		)
	)
	(footprint ""
		(layer "F.Cu")
		(at 291.211 -158.496)
		(property "Reference" "R615"
			(at 0 0 0)
			(layer "F.SilkS")
			(hide yes)
			(effects
				(font
					(size 1.27 1.27)
				)
			)
		)
		(property "Value" "2K2R2J-2-GP"
			(at 0.064008 -3.993896 0)
			(unlocked yes)
			(layer "F.Fab")
			(hide yes)
			(effects
				(font
					(size 1.016 1.016)
					(thickness 0.1524)
				)
			)
		)
		(property "Device Type" "R402H16"
			(at 0.064008 -5.517896 0)
			(unlocked yes)
			(layer "F.Fab")
			(hide yes)
			(effects
				(font
					(size 1.016 1.016)
					(thickness 0.1524)
				)
			)
		)
		(duplicate_pad_numbers_are_jumpers no)
		(fp_line
			(start -0.508 -0.9398)
			(end -0.508 0.9398)
			(stroke
				(width 0.1524)
				(type default)
			)
			(layer "F.SilkS")
		)
		(fp_line
			(start 0.508 -0.9398)
			(end -0.508 -0.9398)
			(stroke
				(width 0.1524)
				(type default)
			)
			(layer "F.SilkS")
		)
		(fp_rect
			(start -0.508 0.9398)
			(end 0.508 -0.9398)
			(stroke
				(width 0)
				(type default)
			)
			(fill no)
			(layer "F.CrtYd")
		)
		(fp_rect
			(start -0.508 0.9398)
			(end 0.508 -0.9398)
			(stroke
				(width 0)
				(type default)
			)
			(fill no)
			(layer "F.Fab")
		)
		(pad "1" smd custom
			(at 0 -0.4445)
			(size 0.1397 0.1397)
			(layers "F.Cu" "F.Mask" "F.Paste")
			(net "CPU_BMC_UART_RX")
			(options
				(clearance outline)
				(anchor circle)
			)
			(primitives
				(gr_poly
					(pts
						(arc
							(start -0.1778 -0.2794)
							(mid -0.249642 -0.249642)
							(end -0.2794 -0.1778)
						)
						(arc
							(start -0.2794 0.1778)
							(mid -0.249642 0.249642)
							(end -0.1778 0.2794)
						)
						(arc
							(start 0.1778 0.2794)
							(mid 0.249642 0.249642)
							(end 0.2794 0.1778)
						)
						(arc
							(start 0.2794 -0.1778)
							(mid 0.249642 -0.249642)
							(end 0.1778 -0.2794)
						)
					)
					(width 0)
					(fill yes)
				)
			)
		)
		(pad "2" smd custom
			(at 0 0.4445)
			(size 0.1397 0.1397)
			(layers "F.Cu" "F.Mask" "F.Paste")
			(net "GND")
			(options
				(clearance outline)
				(anchor circle)
			)
			(primitives
				(gr_poly
					(pts
						(arc
							(start -0.1778 -0.2794)
							(mid -0.249642 -0.249642)
							(end -0.2794 -0.1778)
						)
						(arc
							(start -0.2794 0.1778)
							(mid -0.249642 0.249642)
							(end -0.1778 0.2794)
						)
						(arc
							(start 0.1778 0.2794)
							(mid 0.249642 0.249642)
							(end 0.2794 0.1778)
						)
						(arc
							(start 0.2794 -0.1778)
							(mid 0.249642 -0.249642)
							(end 0.1778 -0.2794)
						)
					)
					(width 0)
					(fill yes)
				)
			)
		)
	)
	(footprint ""
		(layer "F.Cu")
		(at 103.867966 -65.8876 90)
		(property "Reference" "SC916"
			(at 0 0 90)
			(layer "F.SilkS")
			(hide yes)
			(effects
				(font
					(size 1.27 1.27)
				)
			)
		)
		(property "Value" "SC10U6D3V5KX-4GP"
			(at -0.0762 -6.1214 90)
			(unlocked yes)
			(layer "F.Fab")
			(hide yes)
			(effects
				(font
					(size 1.016 1.016)
					(thickness 0.1524)
				)
			)
		)
		(property "Device Type" "C805H58"
			(at -0.0762 -8.1534 90)
			(unlocked yes)
			(layer "F.Fab")
			(hide yes)
			(effects
				(font
					(size 1.016 1.016)
					(thickness 0.1524)
				)
			)
		)
		(duplicate_pad_numbers_are_jumpers no)
		(fp_line
			(start 0.635 0)
			(end -0.635 0)
			(stroke
				(width 0.508)
				(type default)
			)
			(layer "F.SilkS")
		)
		(fp_rect
			(start -0.9652 1.778)
			(end 0.9652 -1.778)
			(stroke
				(width 0)
				(type default)
			)
			(fill no)
			(layer "F.CrtYd")
		)
		(fp_poly
			(pts
				(xy -0.9652 -1.778) (xy 0.9652 -1.778) (xy 0.9652 1.778) (xy -0.9652 1.778)
			)
			(stroke
				(width 0)
				(type default)
			)
			(fill no)
			(layer "F.Fab")
		)
		(pad "1" smd rect
			(at 0 -0.9652 90)
			(size 1.397 1.143)
			(layers "F.Cu" "F.Mask" "F.Paste")
			(net "HM40ADC_VDDA")
		)
		(pad "2" smd rect
			(at 0 0.9652 90)
			(size 1.397 1.143)
			(layers "F.Cu" "F.Mask" "F.Paste")
			(net "GND")
		)
	)
)
